# T6G (Grand Teton) — schematic netlist excerpt (pin names and nets, part order shuffled) for the footprints in the layout excerpt that follows; sources: Cadence DE-HDL packaged netlist, KiCad conversion of 04192023_DAF0TMB3IC0_F0TG_MB_C_brd_V02_OCP.brd

C557  Q_CAP  4.7UF 6.3V 20% X6S  pkg 0402  page 279 : A = P0V9_CPU0_RT0_2A ; B = GND
C2292  Q_CAP  22UF 4V 20% X6S  pkg C0402  page 72 : A = PVDD18_S5_P1 ; B = GND

(kicad_pcb
	(version 20260206)
	(generator "pcbnew")
	(generator_version "10.0")
	(general
		(thickness 1.6)
		(legacy_teardrops no)
	)
	(paper "A4")
	(title_block
		(title "04192023_DAF0TMB3IC0_F0TG_MB_C_brd_V02_OCP.brd")
		(comment 1 "Grand Teton / footprints 7066-7067 of 8354")
	)
	(layers
		(0 "F.Cu" signal "TOP")
		(4 "In1.Cu" signal "GND")
		(6 "In2.Cu" signal "IN1")
		(8 "In3.Cu" signal "GND1")
		(10 "In4.Cu" signal "IN2")
		(12 "In5.Cu" signal "GND2")
		(14 "In6.Cu" signal "IN3")
		(16 "In7.Cu" signal "GND3")
		(18 "In8.Cu" signal "VCC")
		(20 "In9.Cu" signal "VCC1")
		(22 "In10.Cu" signal "GND4")
		(24 "In11.Cu" signal "IN4")
		(26 "In12.Cu" signal "GND5")
		(28 "In13.Cu" signal "IN5")
		(30 "In14.Cu" signal "GND6")
		(32 "In15.Cu" signal "IN6")
		(34 "In16.Cu" signal "GND7")
		(2 "B.Cu" signal "BOTTOM")
		(9 "F.Adhes" user "F.Adhesive")
		(11 "B.Adhes" user "B.Adhesive")
		(13 "F.Paste" user "Package Geometry/Pastemask Top")
		(15 "B.Paste" user "Package Geometry/Pastemask Bottom")
		(5 "F.SilkS" user "Ref Des/Silkscreen Top")
		(7 "B.SilkS" user "Ref Des/Silkscreen Bottom")
		(1 "F.Mask" user "Board Geometry/Soldermask Top")
		(3 "B.Mask" user "Board Geometry/Soldermask Bottom")
		(17 "Dwgs.User" user "User.Drawings")
		(19 "Cmts.User" user "User.Comments")
		(21 "Eco1.User" user "User.Eco1")
		(23 "Eco2.User" user "User.Eco2")
		(25 "Edge.Cuts" user "Board Geometry/Outline")
		(27 "Margin" user)
		(31 "F.CrtYd" user "Package Geometry/Place Bound Top")
		(29 "B.CrtYd" user "Package Geometry/Place Bound Bottom")
		(35 "F.Fab" user "Ref Des/Assembly Top")
		(33 "B.Fab" user "Ref Des/Assembly Bottom")
	)
	(footprint ""
		(layer "B.Cu")
		(at 100.881434 -254.067564 180)
		(property "Reference" "C2292"
			(at 0 0 0)
			(layer "B.SilkS")
			(hide yes)
			(effects
				(font
					(size 1.27 1.27)
				)
				(justify mirror)
			)
		)
		(property "Value" ""
			(at 0 0 0)
			(layer "B.Fab")
			(effects
				(font
					(size 1.27 1.27)
				)
				(justify mirror)
			)
		)
		(duplicate_pad_numbers_are_jumpers no)
		(fp_line
			(start 0.7874 0.4064)
			(end 0.7874 -0.4064)
			(stroke
				(width 0.1524)
				(type default)
			)
			(layer "B.SilkS")
		)
		(fp_line
			(start 0.7874 -0.4064)
			(end -0.7874 -0.4064)
			(stroke
				(width 0.1524)
				(type default)
			)
			(layer "B.SilkS")
		)
		(fp_line
			(start -0.7874 0.4064)
			(end 0.7874 0.4064)
			(stroke
				(width 0.1524)
				(type default)
			)
			(layer "B.SilkS")
		)
		(fp_line
			(start -0.7874 -0.4064)
			(end -0.7874 0.4064)
			(stroke
				(width 0.1524)
				(type default)
			)
			(layer "B.SilkS")
		)
		(fp_line
			(start 0.67945 0.3048)
			(end 0.67945 -0.305054)
			(stroke
				(width 0.1)
				(type default)
			)
			(layer "B.Fab")
		)
		(fp_line
			(start 0.67945 -0.305054)
			(end 0.12065 -0.305054)
			(stroke
				(width 0.1)
				(type default)
			)
			(layer "B.Fab")
		)
		(fp_line
			(start 0.12065 0.3048)
			(end 0.67945 0.3048)
			(stroke
				(width 0.1)
				(type default)
			)
			(layer "B.Fab")
		)
		(fp_line
			(start 0.12065 0.2794)
			(end 0.12065 0.3048)
			(stroke
				(width 0.1)
				(type default)
			)
			(layer "B.Fab")
		)
		(fp_line
			(start 0.12065 -0.2794)
			(end -0.12065 -0.2794)
			(stroke
				(width 0.1)
				(type default)
			)
			(layer "B.Fab")
		)
		(fp_line
			(start 0.12065 -0.305054)
			(end 0.12065 -0.2794)
			(stroke
				(width 0.1)
				(type default)
			)
			(layer "B.Fab")
		)
		(fp_line
			(start -0.120396 0.3048)
			(end -0.120396 0.2794)
			(stroke
				(width 0.1)
				(type default)
			)
			(layer "B.Fab")
		)
		(fp_line
			(start -0.120396 0.2794)
			(end 0.12065 0.2794)
			(stroke
				(width 0.1)
				(type default)
			)
			(layer "B.Fab")
		)
		(fp_line
			(start -0.12065 -0.2794)
			(end -0.12065 -0.3048)
			(stroke
				(width 0.1)
				(type default)
			)
			(layer "B.Fab")
		)
		(fp_line
			(start -0.12065 -0.3048)
			(end -0.67945 -0.3048)
			(stroke
				(width 0.1)
				(type default)
			)
			(layer "B.Fab")
		)
		(fp_line
			(start -0.67945 0.3048)
			(end -0.120396 0.3048)
			(stroke
				(width 0.1)
				(type default)
			)
			(layer "B.Fab")
		)
		(fp_line
			(start -0.67945 -0.3048)
			(end -0.67945 0.3048)
			(stroke
				(width 0.1)
				(type default)
			)
			(layer "B.Fab")
		)
		(pad "1" smd circle
			(at 0.40005 0)
			(size 0 0)
			(layers "B.Cu" "B.Mask" "B.Paste")
			(net "PVDD18_S5_P1")
		)
		(pad "2" smd circle
			(at -0.40005 0)
			(size 0 0)
			(layers "B.Cu" "B.Mask" "B.Paste")
			(net "GND")
		)
	)
	(footprint ""
		(layer "B.Cu")
		(at 305.791108 -398.942052 90)
		(property "Reference" "C557"
			(at 0 0 90)
			(layer "B.SilkS")
			(hide yes)
			(effects
				(font
					(size 1.27 1.27)
				)
				(justify mirror)
			)
		)
		(property "Value" ""
			(at 0 0 90)
			(layer "B.Fab")
			(effects
				(font
					(size 1.27 1.27)
				)
				(justify mirror)
			)
		)
		(duplicate_pad_numbers_are_jumpers no)
		(fp_line
			(start 0.7874 -0.4064)
			(end -0.7874 -0.4064)
			(stroke
				(width 0.1524)
				(type default)
			)
			(layer "B.SilkS")
		)
		(fp_line
			(start -0.7874 -0.4064)
			(end -0.7874 0.4064)
			(stroke
				(width 0.1524)
				(type default)
			)
			(layer "B.SilkS")
		)
		(fp_line
			(start 0.7874 0.4064)
			(end 0.7874 -0.4064)
			(stroke
				(width 0.1524)
				(type default)
			)
			(layer "B.SilkS")
		)
		(fp_line
			(start -0.7874 0.4064)
			(end 0.7874 0.4064)
			(stroke
				(width 0.1524)
				(type default)
			)
			(layer "B.SilkS")
		)
		(fp_line
			(start 0.67945 -0.305054)
			(end 0.12065 -0.305054)
			(stroke
				(width 0.1)
				(type default)
			)
			(layer "B.Fab")
		)
		(fp_line
			(start 0.12065 -0.305054)
			(end 0.12065 -0.2794)
			(stroke
				(width 0.1)
				(type default)
			)
			(layer "B.Fab")
		)
		(fp_line
			(start -0.12065 -0.3048)
			(end -0.67945 -0.3048)
			(stroke
				(width 0.1)
				(type default)
			)
			(layer "B.Fab")
		)
		(fp_line
			(start -0.67945 -0.3048)
			(end -0.67945 0.3048)
			(stroke
				(width 0.1)
				(type default)
			)
			(layer "B.Fab")
		)
		(fp_line
			(start 0.12065 -0.2794)
			(end -0.12065 -0.2794)
			(stroke
				(width 0.1)
				(type default)
			)
			(layer "B.Fab")
		)
		(fp_line
			(start -0.12065 -0.2794)
			(end -0.12065 -0.3048)
			(stroke
				(width 0.1)
				(type default)
			)
			(layer "B.Fab")
		)
		(fp_line
			(start 0.12065 0.2794)
			(end 0.12065 0.3048)
			(stroke
				(width 0.1)
				(type default)
			)
			(layer "B.Fab")
		)
		(fp_line
			(start -0.120396 0.2794)
			(end 0.12065 0.2794)
			(stroke
				(width 0.1)
				(type default)
			)
			(layer "B.Fab")
		)
		(fp_line
			(start 0.67945 0.3048)
			(end 0.67945 -0.305054)
			(stroke
				(width 0.1)
				(type default)
			)
			(layer "B.Fab")
		)
		(fp_line
			(start 0.12065 0.3048)
			(end 0.67945 0.3048)
			(stroke
				(width 0.1)
				(type default)
			)
			(layer "B.Fab")
		)
		(fp_line
			(start -0.120396 0.3048)
			(end -0.120396 0.2794)
			(stroke
				(width 0.1)
				(type default)
			)
			(layer "B.Fab")
		)
		(fp_line
			(start -0.67945 0.3048)
			(end -0.120396 0.3048)
			(stroke
				(width 0.1)
				(type default)
			)
			(layer "B.Fab")
		)
		(pad "1" smd circle
			(at 0.40005 0 270)
			(size 0 0)
			(layers "B.Cu" "B.Mask" "B.Paste")
			(net "P0V9_CPU0_RT0_2A")
		)
		(pad "2" smd circle
			(at -0.40005 0 270)
			(size 0 0)
			(layers "B.Cu" "B.Mask" "B.Paste")
			(net "GND")
		)
	)
)
